(kicad_pcb
	(version 20241229)
	(generator "pcbnew")
	(generator_version "9.0")
	(general
		(thickness 1.6642)
		(legacy_teardrops no)
	)
	(paper "A3")
	(title_block
		(title "PolarFire SoM")
		(date "2025-07-22")
		(rev "1.1.4")
		(company "Antmicro Ltd")
		(comment 1 "www.antmicro.com")
		(comment 9 "footprint 74 of 470 (U12), pads 168-200 of 200")
	)
	(layers
		(0 "F.Cu" mixed)
		(4 "In1.Cu" power)
		(6 "In2.Cu" signal)
		(8 "In3.Cu" power)
		(10 "In4.Cu" signal)
		(12 "In5.Cu" power)
		(14 "In6.Cu" power)
		(16 "In7.Cu" signal)
		(18 "In8.Cu" power)
		(20 "In9.Cu" signal)
		(22 "In10.Cu" power)
		(24 "In11.Cu" signal)
		(26 "In12.Cu" signal)
		(2 "B.Cu" mixed)
		(9 "F.Adhes" user "F.Adhesive")
		(11 "B.Adhes" user "B.Adhesive")
		(13 "F.Paste" user)
		(15 "B.Paste" user)
		(5 "F.SilkS" user "F.Silkscreen")
		(7 "B.SilkS" user "B.Silkscreen")
		(1 "F.Mask" user)
		(3 "B.Mask" user)
		(17 "Dwgs.User" user "User.Drawings")
		(19 "Cmts.User" user "User.Comments")
		(21 "Eco1.User" user "User.Eco1")
		(23 "Eco2.User" user "User.Eco2")
		(25 "Edge.Cuts" user)
		(27 "Margin" user)
		(31 "F.CrtYd" user "F.Courtyard")
		(29 "B.CrtYd" user "B.Courtyard")
		(35 "F.Fab" user)
		(33 "B.Fab" user)
	)
	(footprint "antmicro-footprints:BGA-200_10.0x14.5mm_Layout12x22_P0.80x0.65mm"
		(layer "F.Cu")
		(at 180 129.6)
		(descr "BGA-200, 14.5x10.0mm, 200 Ball, 12x22 Layout, 0.8x0.65mm Pitch, http://www.issi.com/WW/pdf/43-46LQ32256A-AL.pdf")
		(tags "BGA 200 0.8x0.65")
		(property "Reference" "U12"
			(at 6.26 1.53 270)
			(layer "F.SilkS")
			(effects
				(font
					(size 0.7 0.7)
					(thickness 0.15)
				)
				(justify left bottom)
			)
		)
		(property "Value" "MT53D512M32D2_WFBGA"
			(at -5.5 9 0)
			(layer "F.Fab")
			(hide yes)
			(effects
				(font
					(size 0.7 0.7)
					(thickness 0.15)
				)
				(justify left bottom)
			)
		)
		(property "Datasheet" "https://eu.mouser.com/datasheet/2/671/200b_z11m_non_auto_lpddr4_lpddr4x-3077547.pdf"
			(at 0 0 0)
			(layer "F.Fab")
			(hide yes)
			(effects
				(font
					(size 1.27 1.27)
					(thickness 0.15)
				)
			)
		)
		(property "Description" "LPDDR4 DRAM, 1GX32"
			(at 0 0 0)
			(layer "F.Fab")
			(hide yes)
			(effects
				(font
					(size 1.27 1.27)
					(thickness 0.15)
				)
			)
		)
		(property "Author" "Antmicro"
			(at 0 0 0)
			(layer "F.Fab")
			(hide yes)
			(effects
				(font
					(size 1 1)
					(thickness 0.15)
				)
			)
		)
		(property "License" "Apache-2.0"
			(at 0 0 0)
			(layer "F.Fab")
			(hide yes)
			(effects
				(font
					(size 1 1)
					(thickness 0.15)
				)
			)
		)
		(property "MPN" "MT53D512M32D2DS-053 WT:D TR"
			(at 0 0 0)
			(layer "F.Fab")
			(hide yes)
			(effects
				(font
					(size 1 1)
					(thickness 0.15)
				)
			)
		)
		(property "Manufacturer" "Micron Technology"
			(at 0 0 0)
			(layer "F.Fab")
			(hide yes)
			(effects
				(font
					(size 1 1)
					(thickness 0.15)
				)
			)
		)
		(property "VSD_class" "LPDDR4"
			(at 0 0 0)
			(layer "F.Fab")
			(hide yes)
			(effects
				(font
					(size 1 1)
					(thickness 0.15)
				)
			)
		)
		(property ki_fp_filters "WFBGA200_10X14p5_DS_MRN WFBGA200_10X14p5_DS_MRN-M WFBGA200_10X14p5_DS_MRN-L")
		(sheetname "/LPDDR4/")
		(sheetfile "lpddr.kicad_sch")
		(attr smd)
		(pad "U10" smd circle
			(at 2.805 3.567)
			(size 0.27 0.27)
			(layers "F.Cu" "F.Mask" "F.Paste")
			(net 2 "+1V1")
			(pinfunction "VDDQ")
			(pintype "passive")
		)
		(pad "U11" smd circle
			(at 3.604 3.567)
			(size 0.27 0.27)
			(layers "F.Cu" "F.Mask" "F.Paste")
			(net 596 "/FPGA MSS/LPDDR4.DQ27")
			(pinfunction "DQ11_B")
			(pintype "bidirectional")
		)
		(pad "U12" smd circle
			(at 4.405 3.567)
			(size 0.27 0.27)
			(layers "F.Cu" "F.Mask" "F.Paste")
			(net 48 "+1V8")
			(pinfunction "VDD1")
			(pintype "passive")
		)
		(pad "V1" smd circle
			(at -4.396 4.217)
			(size 0.27 0.27)
			(layers "F.Cu" "F.Mask" "F.Paste")
			(net 417 "GND")
			(pinfunction "VSS")
			(pintype "passive")
		)
		(pad "V2" smd circle
			(at -3.596 4.217)
			(size 0.27 0.27)
			(layers "F.Cu" "F.Mask" "F.Paste")
			(net 324 "/FPGA MSS/LPDDR4.DQ18")
			(pinfunction "DQ2_B")
			(pintype "bidirectional")
		)
		(pad "V3" smd circle
			(at -2.795 4.217)
			(size 0.27 0.27)
			(layers "F.Cu" "F.Mask" "F.Paste")
			(net 312 "/FPGA MSS/LPDDR4.DQS2_N")
			(pinfunction "DQS0_c_B")
			(pintype "bidirectional")
		)
		(pad "V4" smd circle
			(at -1.996 4.217)
			(size 0.27 0.27)
			(layers "F.Cu" "F.Mask" "F.Paste")
			(net 600 "/FPGA MSS/LPDDR4.DQ21")
			(pinfunction "DQ5_B")
			(pintype "bidirectional")
		)
		(pad "V5" smd circle
			(at -1.196 4.217)
			(size 0.27 0.27)
			(layers "F.Cu" "F.Mask" "F.Paste")
			(net 417 "GND")
			(pinfunction "VSS")
			(pintype "passive")
		)
		(pad "V8" smd circle
			(at 1.205 4.217)
			(size 0.27 0.27)
			(layers "F.Cu" "F.Mask" "F.Paste")
			(net 417 "GND")
			(pinfunction "VSS")
			(pintype "passive")
		)
		(pad "V9" smd circle
			(at 2.004 4.217)
			(size 0.27 0.27)
			(layers "F.Cu" "F.Mask" "F.Paste")
			(net 585 "/FPGA MSS/LPDDR4.DQ29")
			(pinfunction "DQ13_B")
			(pintype "bidirectional")
		)
		(pad "V10" smd circle
			(at 2.805 4.217)
			(size 0.27 0.27)
			(layers "F.Cu" "F.Mask" "F.Paste")
			(net 599 "/FPGA MSS/LPDDR4.DQS3_N")
			(pinfunction "DQS1_c_B")
			(pintype "bidirectional")
		)
		(pad "V11" smd circle
			(at 3.604 4.217)
			(size 0.27 0.27)
			(layers "F.Cu" "F.Mask" "F.Paste")
			(net 591 "/FPGA MSS/LPDDR4.DQ26")
			(pinfunction "DQ10_B")
			(pintype "bidirectional")
		)
		(pad "V12" smd circle
			(at 4.405 4.217)
			(size 0.27 0.27)
			(layers "F.Cu" "F.Mask" "F.Paste")
			(net 417 "GND")
			(pinfunction "VSS")
			(pintype "passive")
		)
		(pad "W1" smd circle
			(at -4.396 4.866)
			(size 0.27 0.27)
			(layers "F.Cu" "F.Mask" "F.Paste")
			(net 2 "+1V1")
			(pinfunction "VDDQ")
			(pintype "passive")
		)
		(pad "W2" smd circle
			(at -3.596 4.866)
			(size 0.27 0.27)
			(layers "F.Cu" "F.Mask" "F.Paste")
			(net 417 "GND")
			(pinfunction "VSS")
			(pintype "passive")
		)
		(pad "W3" smd circle
			(at -2.795 4.866)
			(size 0.27 0.27)
			(layers "F.Cu" "F.Mask" "F.Paste")
			(net 313 "/FPGA MSS/LPDDR4.DQS2_P")
			(pinfunction "DQS0_t_B")
			(pintype "bidirectional")
		)
		(pad "W4" smd circle
			(at -1.996 4.866)
			(size 0.27 0.27)
			(layers "F.Cu" "F.Mask" "F.Paste")
			(net 417 "GND")
			(pinfunction "VSS")
			(pintype "passive")
		)
		(pad "W5" smd circle
			(at -1.196 4.866)
			(size 0.27 0.27)
			(layers "F.Cu" "F.Mask" "F.Paste")
			(net 2 "+1V1")
			(pinfunction "VDDQ")
			(pintype "passive")
		)
		(pad "W8" smd circle
			(at 1.205 4.866)
			(size 0.27 0.27)
			(layers "F.Cu" "F.Mask" "F.Paste")
			(net 2 "+1V1")
			(pinfunction "VDDQ")
			(pintype "passive")
		)
		(pad "W9" smd circle
			(at 2.004 4.866)
			(size 0.27 0.27)
			(layers "F.Cu" "F.Mask" "F.Paste")
			(net 417 "GND")
			(pinfunction "VSS")
			(pintype "passive")
		)
		(pad "W10" smd circle
			(at 2.805 4.866)
			(size 0.27 0.27)
			(layers "F.Cu" "F.Mask" "F.Paste")
			(net 595 "/FPGA MSS/LPDDR4.DQS3_P")
			(pinfunction "DQS1_t_B")
			(pintype "bidirectional")
		)
		(pad "W11" smd circle
			(at 3.604 4.866)
			(size 0.27 0.27)
			(layers "F.Cu" "F.Mask" "F.Paste")
			(net 417 "GND")
			(pinfunction "VSS")
			(pintype "passive")
		)
		(pad "W12" smd circle
			(at 4.405 4.866)
			(size 0.27 0.27)
			(layers "F.Cu" "F.Mask" "F.Paste")
			(net 2 "+1V1")
			(pinfunction "VDDQ")
			(pintype "passive")
		)
		(pad "Y1" smd circle
			(at -4.396 5.517)
			(size 0.27 0.27)
			(layers "F.Cu" "F.Mask" "F.Paste")
			(net 417 "GND")
			(pinfunction "VSS")
			(pintype "passive")
		)
		(pad "Y2" smd circle
			(at -3.596 5.517)
			(size 0.27 0.27)
			(layers "F.Cu" "F.Mask" "F.Paste")
			(net 605 "/FPGA MSS/LPDDR4.DQ17")
			(pinfunction "DQ1_B")
			(pintype "bidirectional")
		)
		(pad "Y3" smd circle
			(at -2.795 5.517)
			(size 0.27 0.27)
			(layers "F.Cu" "F.Mask" "F.Paste")
			(net 614 "/FPGA MSS/LPDDR4.DMI2")
			(pinfunction "DMI0_B")
			(pintype "bidirectional")
		)
		(pad "Y4" smd circle
			(at -1.996 5.517)
			(size 0.27 0.27)
			(layers "F.Cu" "F.Mask" "F.Paste")
			(net 615 "/FPGA MSS/LPDDR4.DQ22")
			(pinfunction "DQ6_B")
			(pintype "bidirectional")
		)
		(pad "Y5" smd circle
			(at -1.196 5.517)
			(size 0.27 0.27)
			(layers "F.Cu" "F.Mask" "F.Paste")
			(net 417 "GND")
			(pinfunction "VSS")
			(pintype "passive")
		)
		(pad "Y8" smd circle
			(at 1.205 5.517)
			(size 0.27 0.27)
			(layers "F.Cu" "F.Mask" "F.Paste")
			(net 417 "GND")
			(pinfunction "VSS")
			(pintype "passive")
		)
		(pad "Y9" smd circle
			(at 2.004 5.517)
			(size 0.27 0.27)
			(layers "F.Cu" "F.Mask" "F.Paste")
			(net 584 "/FPGA MSS/LPDDR4.DQ30")
			(pinfunction "DQ14_B")
			(pintype "bidirectional")
		)
		(pad "Y10" smd circle
			(at 2.805 5.517)
			(size 0.27 0.27)
			(layers "F.Cu" "F.Mask" "F.Paste")
			(net 590 "/FPGA MSS/LPDDR4.DMI3")
			(pinfunction "DMI1_B")
			(pintype "bidirectional")
		)
		(pad "Y11" smd circle
			(at 3.604 5.517)
			(size 0.27 0.27)
			(layers "F.Cu" "F.Mask" "F.Paste")
			(net 589 "/FPGA MSS/LPDDR4.DQ25")
			(pinfunction "DQ9_B")
			(pintype "bidirectional")
		)
		(pad "Y12" smd circle
			(at 4.405 5.517)
			(size 0.27 0.27)
			(layers "F.Cu" "F.Mask" "F.Paste")
			(net 417 "GND")
			(pinfunction "VSS")
			(pintype "passive")
		)
	)
)
